(kicad_pcb
	(version 20260206)
	(generator "pcbnew")
	(generator_version "10.0")
	(general
		(thickness 1.6)
		(legacy_teardrops no)
	)
	(paper "A4")
	(title_block
		(title "04192023_DAF0TMB3IC0_F0TG_MB_C_brd_V02_OCP.brd")
		(comment 1 "Grand Teton / footprints 3021-3026 of 8354")
	)
	(layers
		(0 "F.Cu" signal "TOP")
		(4 "In1.Cu" signal "GND")
		(6 "In2.Cu" signal "IN1")
		(8 "In3.Cu" signal "GND1")
		(10 "In4.Cu" signal "IN2")
		(12 "In5.Cu" signal "GND2")
		(14 "In6.Cu" signal "IN3")
		(16 "In7.Cu" signal "GND3")
		(18 "In8.Cu" signal "VCC")
		(20 "In9.Cu" signal "VCC1")
		(22 "In10.Cu" signal "GND4")
		(24 "In11.Cu" signal "IN4")
		(26 "In12.Cu" signal "GND5")
		(28 "In13.Cu" signal "IN5")
		(30 "In14.Cu" signal "GND6")
		(32 "In15.Cu" signal "IN6")
		(34 "In16.Cu" signal "GND7")
		(2 "B.Cu" signal "BOTTOM")
		(9 "F.Adhes" user "F.Adhesive")
		(11 "B.Adhes" user "B.Adhesive")
		(13 "F.Paste" user "Package Geometry/Pastemask Top")
		(15 "B.Paste" user "Package Geometry/Pastemask Bottom")
		(5 "F.SilkS" user "Ref Des/Silkscreen Top")
		(7 "B.SilkS" user "Ref Des/Silkscreen Bottom")
		(1 "F.Mask" user "Board Geometry/Soldermask Top")
		(3 "B.Mask" user "Board Geometry/Soldermask Bottom")
		(17 "Dwgs.User" user "User.Drawings")
		(19 "Cmts.User" user "User.Comments")
		(21 "Eco1.User" user "User.Eco1")
		(23 "Eco2.User" user "User.Eco2")
		(25 "Edge.Cuts" user "Board Geometry/Outline")
		(27 "Margin" user)
		(31 "F.CrtYd" user "Package Geometry/Place Bound Top")
		(29 "B.CrtYd" user "Package Geometry/Place Bound Bottom")
		(35 "F.Fab" user "Ref Des/Assembly Top")
		(33 "B.Fab" user "Ref Des/Assembly Bottom")
	)
	(footprint ""
		(layer "F.Cu")
		(at 218.205304 -59.453272 180)
		(property "Reference" "PC2220"
			(at 0 0 180)
			(layer "F.SilkS")
			(hide yes)
			(effects
				(font
					(size 1.27 1.27)
				)
			)
		)
		(property "Value" ""
			(at 0 0 180)
			(layer "F.Fab")
			(effects
				(font
					(size 1.27 1.27)
				)
			)
		)
		(duplicate_pad_numbers_are_jumpers no)
		(fp_line
			(start 1.524 0.762)
			(end -1.524 0.762)
			(stroke
				(width 0.1524)
				(type default)
			)
			(layer "F.SilkS")
		)
		(fp_line
			(start 1.524 -0.762)
			(end 1.524 0.762)
			(stroke
				(width 0.1524)
				(type default)
			)
			(layer "F.SilkS")
		)
		(fp_line
			(start -1.524 0.762)
			(end -1.524 -0.762)
			(stroke
				(width 0.1524)
				(type default)
			)
			(layer "F.SilkS")
		)
		(fp_line
			(start -1.524 -0.762)
			(end 1.524 -0.762)
			(stroke
				(width 0.1524)
				(type default)
			)
			(layer "F.SilkS")
		)
		(fp_line
			(start 1.1049 0.724916)
			(end 1.1049 -0.724916)
			(stroke
				(width 0.1)
				(type default)
			)
			(layer "F.Fab")
		)
		(fp_line
			(start 1.1049 -0.724916)
			(end -1.1049 -0.724916)
			(stroke
				(width 0.1)
				(type default)
			)
			(layer "F.Fab")
		)
		(fp_line
			(start -1.1049 0.724916)
			(end 1.1049 0.724916)
			(stroke
				(width 0.1)
				(type default)
			)
			(layer "F.Fab")
		)
		(fp_line
			(start -1.1049 -0.724916)
			(end -1.1049 0.724916)
			(stroke
				(width 0.1)
				(type default)
			)
			(layer "F.Fab")
		)
		(pad "1" smd rect
			(at -0.889 0)
			(size 1.016 1.27)
			(layers "F.Cu" "F.Mask" "F.Paste")
			(net "P3V3_E1S_0_R")
		)
		(pad "2" smd rect
			(at 0.889 0)
			(size 1.016 1.27)
			(layers "F.Cu" "F.Mask" "F.Paste")
			(net "GND")
		)
	)
	(footprint ""
		(layer "F.Cu")
		(at 381.598678 -142.665958 180)
		(property "Reference" "PR292"
			(at 0 0 180)
			(layer "F.SilkS")
			(hide yes)
			(effects
				(font
					(size 1.27 1.27)
				)
			)
		)
		(property "Value" ""
			(at 0 0 180)
			(layer "F.Fab")
			(effects
				(font
					(size 1.27 1.27)
				)
			)
		)
		(duplicate_pad_numbers_are_jumpers no)
		(fp_line
			(start 0.7874 0.4064)
			(end -0.7874 0.4064)
			(stroke
				(width 0.1524)
				(type default)
			)
			(layer "F.SilkS")
		)
		(fp_line
			(start 0.7874 -0.4064)
			(end 0.7874 0.4064)
			(stroke
				(width 0.1524)
				(type default)
			)
			(layer "F.SilkS")
		)
		(fp_line
			(start -0.7874 0.4064)
			(end -0.7874 -0.4064)
			(stroke
				(width 0.1524)
				(type default)
			)
			(layer "F.SilkS")
		)
		(fp_line
			(start -0.7874 -0.4064)
			(end 0.7874 -0.4064)
			(stroke
				(width 0.1524)
				(type default)
			)
			(layer "F.SilkS")
		)
		(fp_line
			(start 0.67945 0.3048)
			(end 0.120396 0.3048)
			(stroke
				(width 0.1)
				(type default)
			)
			(layer "F.Fab")
		)
		(fp_line
			(start 0.67945 -0.3048)
			(end 0.67945 0.3048)
			(stroke
				(width 0.1)
				(type default)
			)
			(layer "F.Fab")
		)
		(fp_line
			(start 0.12065 -0.2794)
			(end 0.12065 -0.3048)
			(stroke
				(width 0.1)
				(type default)
			)
			(layer "F.Fab")
		)
		(fp_line
			(start 0.12065 -0.3048)
			(end 0.67945 -0.3048)
			(stroke
				(width 0.1)
				(type default)
			)
			(layer "F.Fab")
		)
		(fp_line
			(start 0.120396 0.3048)
			(end 0.120396 0.2794)
			(stroke
				(width 0.1)
				(type default)
			)
			(layer "F.Fab")
		)
		(fp_line
			(start 0.120396 0.2794)
			(end -0.12065 0.2794)
			(stroke
				(width 0.1)
				(type default)
			)
			(layer "F.Fab")
		)
		(fp_line
			(start -0.12065 0.3048)
			(end -0.67945 0.3048)
			(stroke
				(width 0.1)
				(type default)
			)
			(layer "F.Fab")
		)
		(fp_line
			(start -0.12065 0.2794)
			(end -0.12065 0.3048)
			(stroke
				(width 0.1)
				(type default)
			)
			(layer "F.Fab")
		)
		(fp_line
			(start -0.12065 -0.2794)
			(end 0.12065 -0.2794)
			(stroke
				(width 0.1)
				(type default)
			)
			(layer "F.Fab")
		)
		(fp_line
			(start -0.12065 -0.305054)
			(end -0.12065 -0.2794)
			(stroke
				(width 0.1)
				(type default)
			)
			(layer "F.Fab")
		)
		(fp_line
			(start -0.67945 0.3048)
			(end -0.67945 -0.305054)
			(stroke
				(width 0.1)
				(type default)
			)
			(layer "F.Fab")
		)
		(fp_line
			(start -0.67945 -0.305054)
			(end -0.12065 -0.305054)
			(stroke
				(width 0.1)
				(type default)
			)
			(layer "F.Fab")
		)
		(pad "1" smd circle
			(at -0.40005 0 180)
			(size 0 0)
			(layers "F.Cu" "F.Mask" "F.Paste")
			(net "PVDDCR_SOC_P0_EN//ADDR_CFG")
		)
		(pad "2" smd circle
			(at 0.40005 0 180)
			(size 0 0)
			(layers "F.Cu" "F.Mask" "F.Paste")
			(net "GND")
		)
	)
	(footprint ""
		(layer "F.Cu")
		(at 24.917654 -349.386398 90)
		(property "Reference" "PC616"
			(at 0 0 90)
			(layer "F.SilkS")
			(hide yes)
			(effects
				(font
					(size 1.27 1.27)
				)
			)
		)
		(property "Value" ""
			(at 0 0 90)
			(layer "F.Fab")
			(effects
				(font
					(size 1.27 1.27)
				)
			)
		)
		(duplicate_pad_numbers_are_jumpers no)
		(fp_line
			(start 0.7874 -0.4064)
			(end 0.7874 0.4064)
			(stroke
				(width 0.1524)
				(type default)
			)
			(layer "F.SilkS")
		)
		(fp_line
			(start -0.7874 -0.4064)
			(end 0.7874 -0.4064)
			(stroke
				(width 0.1524)
				(type default)
			)
			(layer "F.SilkS")
		)
		(fp_line
			(start 0.7874 0.4064)
			(end 0.498602 0.4064)
			(stroke
				(width 0.1524)
				(type default)
			)
			(layer "F.SilkS")
		)
		(fp_line
			(start -0.314198 0.4064)
			(end -0.7874 0.4064)
			(stroke
				(width 0.1524)
				(type default)
			)
			(layer "F.SilkS")
		)
		(fp_line
			(start -0.7874 0.4064)
			(end -0.7874 -0.4064)
			(stroke
				(width 0.1524)
				(type default)
			)
			(layer "F.SilkS")
		)
		(fp_line
			(start -0.12065 -0.305054)
			(end -0.12065 -0.2794)
			(stroke
				(width 0.1)
				(type default)
			)
			(layer "F.Fab")
		)
		(fp_line
			(start -0.67945 -0.305054)
			(end -0.12065 -0.305054)
			(stroke
				(width 0.1)
				(type default)
			)
			(layer "F.Fab")
		)
		(fp_line
			(start 0.67945 -0.3048)
			(end 0.67945 0.3048)
			(stroke
				(width 0.1)
				(type default)
			)
			(layer "F.Fab")
		)
		(fp_line
			(start 0.12065 -0.3048)
			(end 0.67945 -0.3048)
			(stroke
				(width 0.1)
				(type default)
			)
			(layer "F.Fab")
		)
		(fp_line
			(start 0.12065 -0.2794)
			(end 0.12065 -0.3048)
			(stroke
				(width 0.1)
				(type default)
			)
			(layer "F.Fab")
		)
		(fp_line
			(start -0.12065 -0.2794)
			(end 0.12065 -0.2794)
			(stroke
				(width 0.1)
				(type default)
			)
			(layer "F.Fab")
		)
		(fp_line
			(start 0.120396 0.2794)
			(end -0.12065 0.2794)
			(stroke
				(width 0.1)
				(type default)
			)
			(layer "F.Fab")
		)
		(fp_line
			(start -0.12065 0.2794)
			(end -0.12065 0.3048)
			(stroke
				(width 0.1)
				(type default)
			)
			(layer "F.Fab")
		)
		(fp_line
			(start 0.67945 0.3048)
			(end 0.120396 0.3048)
			(stroke
				(width 0.1)
				(type default)
			)
			(layer "F.Fab")
		)
		(fp_line
			(start 0.120396 0.3048)
			(end 0.120396 0.2794)
			(stroke
				(width 0.1)
				(type default)
			)
			(layer "F.Fab")
		)
		(fp_line
			(start -0.12065 0.3048)
			(end -0.67945 0.3048)
			(stroke
				(width 0.1)
				(type default)
			)
			(layer "F.Fab")
		)
		(fp_line
			(start -0.67945 0.3048)
			(end -0.67945 -0.305054)
			(stroke
				(width 0.1)
				(type default)
			)
			(layer "F.Fab")
		)
		(pad "1" smd circle
			(at -0.40005 0 90)
			(size 0 0)
			(layers "F.Cu" "F.Mask" "F.Paste")
			(net "PVDDIO_P1_VCC4")
		)
		(pad "2" smd circle
			(at 0.40005 0 90)
			(size 0 0)
			(layers "F.Cu" "F.Mask" "F.Paste")
			(net "GND")
		)
	)
	(footprint ""
		(layer "F.Cu")
		(at 120.68175 -28.085796)
		(property "Reference" "R6266"
			(at 0 0 0)
			(layer "F.SilkS")
			(hide yes)
			(effects
				(font
					(size 1.27 1.27)
				)
			)
		)
		(property "Value" ""
			(at 0 0 0)
			(layer "F.Fab")
			(effects
				(font
					(size 1.27 1.27)
				)
			)
		)
		(duplicate_pad_numbers_are_jumpers no)
		(fp_line
			(start -0.7874 -0.4064)
			(end 0.7874 -0.4064)
			(stroke
				(width 0.1524)
				(type default)
			)
			(layer "F.SilkS")
		)
		(fp_line
			(start -0.7874 0.4064)
			(end -0.7874 -0.4064)
			(stroke
				(width 0.1524)
				(type default)
			)
			(layer "F.SilkS")
		)
		(fp_line
			(start 0.7874 -0.4064)
			(end 0.7874 0.4064)
			(stroke
				(width 0.1524)
				(type default)
			)
			(layer "F.SilkS")
		)
		(fp_line
			(start 0.7874 0.4064)
			(end -0.7874 0.4064)
			(stroke
				(width 0.1524)
				(type default)
			)
			(layer "F.SilkS")
		)
		(fp_line
			(start -0.67945 -0.305054)
			(end -0.12065 -0.305054)
			(stroke
				(width 0.1)
				(type default)
			)
			(layer "F.Fab")
		)
		(fp_line
			(start -0.67945 0.3048)
			(end -0.67945 -0.305054)
			(stroke
				(width 0.1)
				(type default)
			)
			(layer "F.Fab")
		)
		(fp_line
			(start -0.12065 -0.305054)
			(end -0.12065 -0.2794)
			(stroke
				(width 0.1)
				(type default)
			)
			(layer "F.Fab")
		)
		(fp_line
			(start -0.12065 -0.2794)
			(end 0.12065 -0.2794)
			(stroke
				(width 0.1)
				(type default)
			)
			(layer "F.Fab")
		)
		(fp_line
			(start -0.12065 0.2794)
			(end -0.12065 0.3048)
			(stroke
				(width 0.1)
				(type default)
			)
			(layer "F.Fab")
		)
		(fp_line
			(start -0.12065 0.3048)
			(end -0.67945 0.3048)
			(stroke
				(width 0.1)
				(type default)
			)
			(layer "F.Fab")
		)
		(fp_line
			(start 0.120396 0.2794)
			(end -0.12065 0.2794)
			(stroke
				(width 0.1)
				(type default)
			)
			(layer "F.Fab")
		)
		(fp_line
			(start 0.120396 0.3048)
			(end 0.120396 0.2794)
			(stroke
				(width 0.1)
				(type default)
			)
			(layer "F.Fab")
		)
		(fp_line
			(start 0.12065 -0.3048)
			(end 0.67945 -0.3048)
			(stroke
				(width 0.1)
				(type default)
			)
			(layer "F.Fab")
		)
		(fp_line
			(start 0.12065 -0.2794)
			(end 0.12065 -0.3048)
			(stroke
				(width 0.1)
				(type default)
			)
			(layer "F.Fab")
		)
		(fp_line
			(start 0.67945 -0.3048)
			(end 0.67945 0.3048)
			(stroke
				(width 0.1)
				(type default)
			)
			(layer "F.Fab")
		)
		(fp_line
			(start 0.67945 0.3048)
			(end 0.120396 0.3048)
			(stroke
				(width 0.1)
				(type default)
			)
			(layer "F.Fab")
		)
		(pad "1" smd circle
			(at -0.40005 0)
			(size 0 0)
			(layers "F.Cu" "F.Mask" "F.Paste")
			(net "USB_HUB2_TI_USB_SSRXM_DN3_MRP_VDD12")
		)
		(pad "2" smd circle
			(at 0.40005 0)
			(size 0 0)
			(layers "F.Cu" "F.Mask" "F.Paste")
			(net "P1V2_CPU0_USB2_DVDD12")
		)
	)
	(footprint ""
		(layer "F.Cu")
		(at 156.154628 -45.64888 180)
		(property "Reference" "C1305"
			(at 0 0 180)
			(layer "F.SilkS")
			(hide yes)
			(effects
				(font
					(size 1.27 1.27)
				)
			)
		)
		(property "Value" ""
			(at 0 0 180)
			(layer "F.Fab")
			(effects
				(font
					(size 1.27 1.27)
				)
			)
		)
		(duplicate_pad_numbers_are_jumpers no)
		(fp_line
			(start 0.7874 0.4064)
			(end -0.7874 0.4064)
			(stroke
				(width 0.1524)
				(type default)
			)
			(layer "F.SilkS")
		)
		(fp_line
			(start 0.7874 -0.4064)
			(end 0.7874 0.4064)
			(stroke
				(width 0.1524)
				(type default)
			)
			(layer "F.SilkS")
		)
		(fp_line
			(start -0.7874 0.4064)
			(end -0.7874 -0.4064)
			(stroke
				(width 0.1524)
				(type default)
			)
			(layer "F.SilkS")
		)
		(fp_line
			(start -0.7874 -0.4064)
			(end 0.7874 -0.4064)
			(stroke
				(width 0.1524)
				(type default)
			)
			(layer "F.SilkS")
		)
		(fp_line
			(start 0.67945 0.3048)
			(end 0.120396 0.3048)
			(stroke
				(width 0.1)
				(type default)
			)
			(layer "F.Fab")
		)
		(fp_line
			(start 0.67945 -0.3048)
			(end 0.67945 0.3048)
			(stroke
				(width 0.1)
				(type default)
			)
			(layer "F.Fab")
		)
		(fp_line
			(start 0.12065 -0.2794)
			(end 0.12065 -0.3048)
			(stroke
				(width 0.1)
				(type default)
			)
			(layer "F.Fab")
		)
		(fp_line
			(start 0.12065 -0.3048)
			(end 0.67945 -0.3048)
			(stroke
				(width 0.1)
				(type default)
			)
			(layer "F.Fab")
		)
		(fp_line
			(start 0.120396 0.3048)
			(end 0.120396 0.2794)
			(stroke
				(width 0.1)
				(type default)
			)
			(layer "F.Fab")
		)
		(fp_line
			(start 0.120396 0.2794)
			(end -0.12065 0.2794)
			(stroke
				(width 0.1)
				(type default)
			)
			(layer "F.Fab")
		)
		(fp_line
			(start -0.12065 0.3048)
			(end -0.67945 0.3048)
			(stroke
				(width 0.1)
				(type default)
			)
			(layer "F.Fab")
		)
		(fp_line
			(start -0.12065 0.2794)
			(end -0.12065 0.3048)
			(stroke
				(width 0.1)
				(type default)
			)
			(layer "F.Fab")
		)
		(fp_line
			(start -0.12065 -0.2794)
			(end 0.12065 -0.2794)
			(stroke
				(width 0.1)
				(type default)
			)
			(layer "F.Fab")
		)
		(fp_line
			(start -0.12065 -0.305054)
			(end -0.12065 -0.2794)
			(stroke
				(width 0.1)
				(type default)
			)
			(layer "F.Fab")
		)
		(fp_line
			(start -0.67945 0.3048)
			(end -0.67945 -0.305054)
			(stroke
				(width 0.1)
				(type default)
			)
			(layer "F.Fab")
		)
		(fp_line
			(start -0.67945 -0.305054)
			(end -0.12065 -0.305054)
			(stroke
				(width 0.1)
				(type default)
			)
			(layer "F.Fab")
		)
		(pad "1" smd circle
			(at -0.40005 0 180)
			(size 0 0)
			(layers "F.Cu" "F.Mask" "F.Paste")
			(net "P3V3_AUX")
		)
		(pad "2" smd circle
			(at 0.40005 0 180)
			(size 0 0)
			(layers "F.Cu" "F.Mask" "F.Paste")
			(net "GND")
		)
	)
	(footprint ""
		(layer "F.Cu")
		(at 320.981324 -192.89776 -90)
		(property "Reference" "R426"
			(at 0 0 270)
			(layer "F.SilkS")
			(hide yes)
			(effects
				(font
					(size 1.27 1.27)
				)
			)
		)
		(property "Value" ""
			(at 0 0 270)
			(layer "F.Fab")
			(effects
				(font
					(size 1.27 1.27)
				)
			)
		)
		(duplicate_pad_numbers_are_jumpers no)
		(fp_line
			(start -0.7874 0.4064)
			(end -0.7874 -0.4064)
			(stroke
				(width 0.1524)
				(type default)
			)
			(layer "F.SilkS")
		)
		(fp_line
			(start 0.7874 0.4064)
			(end -0.7874 0.4064)
			(stroke
				(width 0.1524)
				(type default)
			)
			(layer "F.SilkS")
		)
		(fp_line
			(start -0.7874 -0.4064)
			(end 0.7874 -0.4064)
			(stroke
				(width 0.1524)
				(type default)
			)
			(layer "F.SilkS")
		)
		(fp_line
			(start 0.7874 -0.4064)
			(end 0.7874 0.4064)
			(stroke
				(width 0.1524)
				(type default)
			)
			(layer "F.SilkS")
		)
		(fp_line
			(start -0.67945 0.3048)
			(end -0.67945 -0.305054)
			(stroke
				(width 0.1)
				(type default)
			)
			(layer "F.Fab")
		)
		(fp_line
			(start -0.12065 0.3048)
			(end -0.67945 0.3048)
			(stroke
				(width 0.1)
				(type default)
			)
			(layer "F.Fab")
		)
		(fp_line
			(start 0.120396 0.3048)
			(end 0.120396 0.2794)
			(stroke
				(width 0.1)
				(type default)
			)
			(layer "F.Fab")
		)
		(fp_line
			(start 0.67945 0.3048)
			(end 0.120396 0.3048)
			(stroke
				(width 0.1)
				(type default)
			)
			(layer "F.Fab")
		)
		(fp_line
			(start -0.12065 0.2794)
			(end -0.12065 0.3048)
			(stroke
				(width 0.1)
				(type default)
			)
			(layer "F.Fab")
		)
		(fp_line
			(start 0.120396 0.2794)
			(end -0.12065 0.2794)
			(stroke
				(width 0.1)
				(type default)
			)
			(layer "F.Fab")
		)
		(fp_line
			(start -0.12065 -0.2794)
			(end 0.12065 -0.2794)
			(stroke
				(width 0.1)
				(type default)
			)
			(layer "F.Fab")
		)
		(fp_line
			(start 0.12065 -0.2794)
			(end 0.12065 -0.3048)
			(stroke
				(width 0.1)
				(type default)
			)
			(layer "F.Fab")
		)
		(fp_line
			(start 0.12065 -0.3048)
			(end 0.67945 -0.3048)
			(stroke
				(width 0.1)
				(type default)
			)
			(layer "F.Fab")
		)
		(fp_line
			(start 0.67945 -0.3048)
			(end 0.67945 0.3048)
			(stroke
				(width 0.1)
				(type default)
			)
			(layer "F.Fab")
		)
		(fp_line
			(start -0.67945 -0.305054)
			(end -0.12065 -0.305054)
			(stroke
				(width 0.1)
				(type default)
			)
			(layer "F.Fab")
		)
		(fp_line
			(start -0.12065 -0.305054)
			(end -0.12065 -0.2794)
			(stroke
				(width 0.1)
				(type default)
			)
			(layer "F.Fab")
		)
		(pad "1" smd rect
			(at -0.40005 0 90)
			(size 0.4572 0.508)
			(layers "F.Cu" "F.Mask" "F.Paste")
			(net "I3C_0_SPD_DDRAF_CPU0_SCL")
		)
		(pad "2" smd rect
			(at 0.40005 0 90)
			(size 0.4572 0.508)
			(layers "F.Cu" "F.Mask" "F.Paste")
			(net "I3C_0_SPD_DDRAF_CPU0_R_SCL")
		)
	)
)
